(kicad_pcb
	(version 20260206)
	(generator "pcbnew")
	(generator_version "10.0")
	(general
		(thickness 1.6)
		(legacy_teardrops no)
	)
	(paper "A4")
	(title_block
		(title "01162023_DA0F0TEBIF0_F0T_Expander_BD_F_brd_V02_OCP.brd")
		(comment 1 "Grand Teton / footprints 8575-8580 of 9728")
	)
	(layers
		(0 "F.Cu" signal "TOP")
		(4 "In1.Cu" signal "GND")
		(6 "In2.Cu" signal "VCC")
		(8 "In3.Cu" signal "VCC1")
		(10 "In4.Cu" signal "GND1")
		(12 "In5.Cu" signal "IN1")
		(14 "In6.Cu" signal "GND2")
		(16 "In7.Cu" signal "IN2")
		(18 "In8.Cu" signal "GND3")
		(20 "In9.Cu" signal "IN3")
		(22 "In10.Cu" signal "GND4")
		(24 "In11.Cu" signal "IN4")
		(26 "In12.Cu" signal "GND5")
		(28 "In13.Cu" signal "IN5")
		(30 "In14.Cu" signal "GND6")
		(32 "In15.Cu" signal "IN6")
		(34 "In16.Cu" signal "GND7")
		(2 "B.Cu" signal "BOTTOM")
		(9 "F.Adhes" user "F.Adhesive")
		(11 "B.Adhes" user "B.Adhesive")
		(13 "F.Paste" user "Package Geometry/Pastemask Top")
		(15 "B.Paste" user "Package Geometry/Pastemask Bottom")
		(5 "F.SilkS" user "Ref Des/Silkscreen Top")
		(7 "B.SilkS" user "Ref Des/Silkscreen Bottom")
		(1 "F.Mask" user "Board Geometry/Soldermask Top")
		(3 "B.Mask" user "Board Geometry/Soldermask Bottom")
		(17 "Dwgs.User" user "User.Drawings")
		(19 "Cmts.User" user "User.Comments")
		(21 "Eco1.User" user "User.Eco1")
		(23 "Eco2.User" user "User.Eco2")
		(25 "Edge.Cuts" user "Board Geometry/Outline")
		(27 "Margin" user)
		(31 "F.CrtYd" user "Package Geometry/Place Bound Top")
		(29 "B.CrtYd" user "Package Geometry/Place Bound Bottom")
		(35 "F.Fab" user "Ref Des/Assembly Top")
		(33 "B.Fab" user "Ref Des/Assembly Bottom")
	)
	(footprint ""
		(layer "B.Cu")
		(at 183.326024 8.083804 180)
		(property "Reference" "DE12T_1"
			(at 3.6068 -2.962148 180)
			(unlocked yes)
			(layer "B.SilkS")
			(effects
				(font
					(size 0.7874 0.5842)
					(thickness 0.1524)
				)
				(justify left mirror)
			)
		)
		(property "Value" ""
			(at 0 0 0)
			(layer "B.Fab")
			(effects
				(font
					(size 1.27 1.27)
				)
				(justify mirror)
			)
		)
		(duplicate_pad_numbers_are_jumpers no)
		(fp_line
			(start 1.2192 2.1082)
			(end 1.2192 -2.1082)
			(stroke
				(width 0.1524)
				(type default)
			)
			(layer "B.SilkS")
		)
		(fp_line
			(start 1.2192 -2.1082)
			(end -1.2192 -2.1082)
			(stroke
				(width 0.1524)
				(type default)
			)
			(layer "B.SilkS")
		)
		(fp_line
			(start -1.2192 2.1082)
			(end 1.2192 2.1082)
			(stroke
				(width 0.1524)
				(type default)
			)
			(layer "B.SilkS")
		)
		(fp_line
			(start -1.2192 -2.1082)
			(end -1.2192 2.1082)
			(stroke
				(width 0.1524)
				(type default)
			)
			(layer "B.SilkS")
		)
		(pad "" np_thru_hole circle
			(at -3.4671 -1.27 90)
			(size 1.0414 1.0414)
			(drill 1.0414)
			(layers "*.Cu" "*.Mask")
			(clearance 0.381)
			(thermal_gap 0.381)
		)
		(pad "" np_thru_hole circle
			(at -3.4671 1.27 90)
			(size 1.0414 1.0414)
			(drill 1.0414)
			(layers "*.Cu" "*.Mask")
			(clearance 0.381)
			(thermal_gap 0.381)
		)
		(pad "" np_thru_hole circle
			(at 2.8829 -1.27 90)
			(size 1.0414 1.0414)
			(drill 1.0414)
			(layers "*.Cu" "*.Mask")
			(clearance 0.381)
			(thermal_gap 0.381)
		)
		(pad "" np_thru_hole circle
			(at 2.8829 1.27 90)
			(size 1.0414 1.0414)
			(drill 1.0414)
			(layers "*.Cu" "*.Mask")
			(clearance 0.381)
			(thermal_gap 0.381)
		)
		(pad "1" smd rect
			(at -0.8255 -0.249936 90)
			(size 0.3048 0.508)
			(layers "B.Cu" "B.Mask" "B.Paste")
			(net "85_10INCH_BOTTOM_DP")
		)
		(pad "2" smd rect
			(at -0.8255 0.249936 90)
			(size 0.3048 0.508)
			(layers "B.Cu" "B.Mask" "B.Paste")
			(net "85_10INCH_BOTTOM_DN")
		)
		(pad "3" smd circle
			(at 0 0)
			(size 0 0)
			(layers "B.Cu" "B.Mask" "B.Paste")
			(net "COUPON_GND2")
		)
		(zone
			(layers "F.Cu" "B.Cu" "In1.Cu" "In2.Cu" "In3.Cu" "In4.Cu" "In5.Cu" "In6.Cu"
				"In7.Cu" "In8.Cu" "In9.Cu" "In10.Cu" "In11.Cu" "In12.Cu" "In13.Cu" "In14.Cu"
				"In15.Cu" "In16.Cu"
			)
			(hatch none 0.5)
			(connect_pads
				(clearance 0)
			)
			(min_thickness 0.25)
			(keepout
				(tracks not_allowed)
				(vias allowed)
				(pads allowed)
				(copperpour not_allowed)
				(footprints allowed)
			)
			(placement
				(enabled no)
				(sheetname "")
			)
			(fill
				(thermal_gap 0.5)
				(thermal_bridge_width 0.5)
				(island_removal_mode 0)
			)
			(polygon
				(pts
					(arc
						(start 181.370224 6.813804)
						(mid 179.516024 6.813804)
						(end 181.370224 6.813804)
					)
				)
			)
		)
		(zone
			(layers "F.Cu" "B.Cu" "In1.Cu" "In2.Cu" "In3.Cu" "In4.Cu" "In5.Cu" "In6.Cu"
				"In7.Cu" "In8.Cu" "In9.Cu" "In10.Cu" "In11.Cu" "In12.Cu" "In13.Cu" "In14.Cu"
				"In15.Cu" "In16.Cu"
			)
			(hatch none 0.5)
			(connect_pads
				(clearance 0)
			)
			(min_thickness 0.25)
			(keepout
				(tracks not_allowed)
				(vias allowed)
				(pads allowed)
				(copperpour not_allowed)
				(footprints allowed)
			)
			(placement
				(enabled no)
				(sheetname "")
			)
			(fill
				(thermal_gap 0.5)
				(thermal_bridge_width 0.5)
				(island_removal_mode 0)
			)
			(polygon
				(pts
					(arc
						(start 181.370224 9.353804)
						(mid 179.516024 9.353804)
						(end 181.370224 9.353804)
					)
				)
			)
		)
		(zone
			(layers "F.Cu" "B.Cu" "In1.Cu" "In2.Cu" "In3.Cu" "In4.Cu" "In5.Cu" "In6.Cu"
				"In7.Cu" "In8.Cu" "In9.Cu" "In10.Cu" "In11.Cu" "In12.Cu" "In13.Cu" "In14.Cu"
				"In15.Cu" "In16.Cu"
			)
			(hatch none 0.5)
			(connect_pads
				(clearance 0)
			)
			(min_thickness 0.25)
			(keepout
				(tracks not_allowed)
				(vias allowed)
				(pads allowed)
				(copperpour not_allowed)
				(footprints allowed)
			)
			(placement
				(enabled no)
				(sheetname "")
			)
			(fill
				(thermal_gap 0.5)
				(thermal_bridge_width 0.5)
				(island_removal_mode 0)
			)
			(polygon
				(pts
					(arc
						(start 187.720224 6.813804)
						(mid 185.866024 6.813804)
						(end 187.720224 6.813804)
					)
				)
			)
		)
		(zone
			(layers "F.Cu" "B.Cu" "In1.Cu" "In2.Cu" "In3.Cu" "In4.Cu" "In5.Cu" "In6.Cu"
				"In7.Cu" "In8.Cu" "In9.Cu" "In10.Cu" "In11.Cu" "In12.Cu" "In13.Cu" "In14.Cu"
				"In15.Cu" "In16.Cu"
			)
			(hatch none 0.5)
			(connect_pads
				(clearance 0)
			)
			(min_thickness 0.25)
			(keepout
				(tracks not_allowed)
				(vias allowed)
				(pads allowed)
				(copperpour not_allowed)
				(footprints allowed)
			)
			(placement
				(enabled no)
				(sheetname "")
			)
			(fill
				(thermal_gap 0.5)
				(thermal_bridge_width 0.5)
				(island_removal_mode 0)
			)
			(polygon
				(pts
					(arc
						(start 187.720224 9.353804)
						(mid 185.866024 9.353804)
						(end 187.720224 9.353804)
					)
				)
			)
		)
		(zone
			(layer "B.Cu")
			(hatch none 0.5)
			(connect_pads
				(clearance 0)
			)
			(min_thickness 0.25)
			(keepout
				(tracks not_allowed)
				(vias allowed)
				(pads allowed)
				(copperpour not_allowed)
				(footprints allowed)
			)
			(placement
				(enabled no)
				(sheetname "")
			)
			(fill
				(thermal_gap 0.5)
				(thermal_bridge_width 0.5)
				(island_removal_mode 0)
			)
			(polygon
				(pts
					(xy 184.443624 8.632444) (xy 184.443624 8.53694) (xy 183.846724 8.53694) (xy 183.846724 8.13054)
					(xy 184.443624 8.13054) (xy 184.443624 8.037068) (xy 183.846724 8.037068) (xy 183.846724 7.630668)
					(xy 184.443624 7.630668) (xy 184.443624 7.535164) (xy 183.745124 7.535164) (xy 183.745124 8.632444)
				)
			)
		)
	)
	(footprint ""
		(layer "B.Cu")
		(at 403.61997 -305.399948 -90)
		(property "Reference" "C3498"
			(at 0 0 90)
			(layer "B.SilkS")
			(hide yes)
			(effects
				(font
					(size 1.27 1.27)
				)
				(justify mirror)
			)
		)
		(property "Value" ""
			(at 0 0 90)
			(layer "B.Fab")
			(effects
				(font
					(size 1.27 1.27)
				)
				(justify mirror)
			)
		)
		(duplicate_pad_numbers_are_jumpers no)
		(fp_line
			(start -0.299974 0.150114)
			(end 0.299974 0.150114)
			(stroke
				(width 0.1)
				(type default)
			)
			(layer "B.Fab")
		)
		(fp_line
			(start 0.299974 0.150114)
			(end 0.299974 -0.150114)
			(stroke
				(width 0.1)
				(type default)
			)
			(layer "B.Fab")
		)
		(fp_line
			(start -0.299974 -0.150114)
			(end -0.299974 0.150114)
			(stroke
				(width 0.1)
				(type default)
			)
			(layer "B.Fab")
		)
		(fp_line
			(start 0.299974 -0.150114)
			(end -0.299974 -0.150114)
			(stroke
				(width 0.1)
				(type default)
			)
			(layer "B.Fab")
		)
		(pad "1" smd rect
			(at 0.2667 0 90)
			(size 0.3048 0.381)
			(layers "B.Cu" "B.Mask" "B.Paste")
			(net "P1V25_SERDES_VDDPLL_PEX3")
		)
		(pad "2" smd rect
			(at -0.2667 0 90)
			(size 0.3048 0.381)
			(layers "B.Cu" "B.Mask" "B.Paste")
			(net "GND")
		)
	)
	(footprint ""
		(layer "B.Cu")
		(at 143.822674 -214.959184 90)
		(property "Reference" "R988"
			(at 0 0 90)
			(layer "B.SilkS")
			(hide yes)
			(effects
				(font
					(size 1.27 1.27)
				)
				(justify mirror)
			)
		)
		(property "Value" ""
			(at 0 0 90)
			(layer "B.Fab")
			(effects
				(font
					(size 1.27 1.27)
				)
				(justify mirror)
			)
		)
		(duplicate_pad_numbers_are_jumpers no)
		(fp_line
			(start 0.7874 -0.4064)
			(end -0.7874 -0.4064)
			(stroke
				(width 0.1524)
				(type default)
			)
			(layer "B.SilkS")
		)
		(fp_line
			(start -0.7874 -0.4064)
			(end -0.7874 0.4064)
			(stroke
				(width 0.1524)
				(type default)
			)
			(layer "B.SilkS")
		)
		(fp_line
			(start 0.7874 0.4064)
			(end 0.7874 -0.4064)
			(stroke
				(width 0.1524)
				(type default)
			)
			(layer "B.SilkS")
		)
		(fp_line
			(start -0.7874 0.4064)
			(end 0.7874 0.4064)
			(stroke
				(width 0.1524)
				(type default)
			)
			(layer "B.SilkS")
		)
		(fp_line
			(start 0.67945 -0.305054)
			(end 0.12065 -0.305054)
			(stroke
				(width 0.1)
				(type default)
			)
			(layer "B.Fab")
		)
		(fp_line
			(start 0.12065 -0.305054)
			(end 0.12065 -0.2794)
			(stroke
				(width 0.1)
				(type default)
			)
			(layer "B.Fab")
		)
		(fp_line
			(start -0.12065 -0.3048)
			(end -0.67945 -0.3048)
			(stroke
				(width 0.1)
				(type default)
			)
			(layer "B.Fab")
		)
		(fp_line
			(start -0.67945 -0.3048)
			(end -0.67945 0.3048)
			(stroke
				(width 0.1)
				(type default)
			)
			(layer "B.Fab")
		)
		(fp_line
			(start 0.12065 -0.2794)
			(end -0.12065 -0.2794)
			(stroke
				(width 0.1)
				(type default)
			)
			(layer "B.Fab")
		)
		(fp_line
			(start -0.12065 -0.2794)
			(end -0.12065 -0.3048)
			(stroke
				(width 0.1)
				(type default)
			)
			(layer "B.Fab")
		)
		(fp_line
			(start 0.12065 0.2794)
			(end 0.12065 0.3048)
			(stroke
				(width 0.1)
				(type default)
			)
			(layer "B.Fab")
		)
		(fp_line
			(start -0.120396 0.2794)
			(end 0.12065 0.2794)
			(stroke
				(width 0.1)
				(type default)
			)
			(layer "B.Fab")
		)
		(fp_line
			(start 0.67945 0.3048)
			(end 0.67945 -0.305054)
			(stroke
				(width 0.1)
				(type default)
			)
			(layer "B.Fab")
		)
		(fp_line
			(start 0.12065 0.3048)
			(end 0.67945 0.3048)
			(stroke
				(width 0.1)
				(type default)
			)
			(layer "B.Fab")
		)
		(fp_line
			(start -0.120396 0.3048)
			(end -0.120396 0.2794)
			(stroke
				(width 0.1)
				(type default)
			)
			(layer "B.Fab")
		)
		(fp_line
			(start -0.67945 0.3048)
			(end -0.120396 0.3048)
			(stroke
				(width 0.1)
				(type default)
			)
			(layer "B.Fab")
		)
		(pad "1" smd circle
			(at 0.40005 0 270)
			(size 0 0)
			(layers "B.Cu" "B.Mask" "B.Paste")
			(net "UART_PEX2_CLI_BUF_RX")
		)
		(pad "2" smd circle
			(at -0.40005 0 270)
			(size 0 0)
			(layers "B.Cu" "B.Mask" "B.Paste")
			(net "P1V8_PEX")
		)
	)
	(footprint ""
		(layer "B.Cu")
		(at 273.115024 20.575524 180)
		(property "Reference" "DE06F_4"
			(at -2.652776 -2.971546 0)
			(unlocked yes)
			(layer "B.SilkS")
			(effects
				(font
					(size 0.7874 0.5842)
					(thickness 0.1524)
				)
				(justify left mirror)
			)
		)
		(property "Value" ""
			(at 0 0 0)
			(layer "B.Fab")
			(effects
				(font
					(size 1.27 1.27)
				)
				(justify mirror)
			)
		)
		(duplicate_pad_numbers_are_jumpers no)
		(fp_line
			(start 1.2192 2.1082)
			(end 1.2192 -2.1082)
			(stroke
				(width 0.1524)
				(type default)
			)
			(layer "B.SilkS")
		)
		(fp_line
			(start 1.2192 -2.1082)
			(end -1.2192 -2.1082)
			(stroke
				(width 0.1524)
				(type default)
			)
			(layer "B.SilkS")
		)
		(fp_line
			(start -1.2192 2.1082)
			(end 1.2192 2.1082)
			(stroke
				(width 0.1524)
				(type default)
			)
			(layer "B.SilkS")
		)
		(fp_line
			(start -1.2192 -2.1082)
			(end -1.2192 2.1082)
			(stroke
				(width 0.1524)
				(type default)
			)
			(layer "B.SilkS")
		)
		(pad "" np_thru_hole circle
			(at -3.4671 -1.27 90)
			(size 1.0414 1.0414)
			(drill 1.0414)
			(layers "*.Cu" "*.Mask")
			(clearance 0.381)
			(thermal_gap 0.381)
		)
		(pad "" np_thru_hole circle
			(at -3.4671 1.27 90)
			(size 1.0414 1.0414)
			(drill 1.0414)
			(layers "*.Cu" "*.Mask")
			(clearance 0.381)
			(thermal_gap 0.381)
		)
		(pad "" np_thru_hole circle
			(at 2.8829 -1.27 90)
			(size 1.0414 1.0414)
			(drill 1.0414)
			(layers "*.Cu" "*.Mask")
			(clearance 0.381)
			(thermal_gap 0.381)
		)
		(pad "" np_thru_hole circle
			(at 2.8829 1.27 90)
			(size 1.0414 1.0414)
			(drill 1.0414)
			(layers "*.Cu" "*.Mask")
			(clearance 0.381)
			(thermal_gap 0.381)
		)
		(pad "1" smd rect
			(at -0.8255 -0.249936 90)
			(size 0.3048 0.508)
			(layers "B.Cu" "B.Mask" "B.Paste")
			(net "85_5INCH_IN6_DN")
		)
		(pad "2" smd rect
			(at -0.8255 0.249936 90)
			(size 0.3048 0.508)
			(layers "B.Cu" "B.Mask" "B.Paste")
			(net "85_5INCH_IN6_DP")
		)
		(pad "3" smd circle
			(at 0 0)
			(size 0 0)
			(layers "B.Cu" "B.Mask" "B.Paste")
			(net "COUPON_GND2")
		)
		(zone
			(layers "F.Cu" "B.Cu" "In1.Cu" "In2.Cu" "In3.Cu" "In4.Cu" "In5.Cu" "In6.Cu"
				"In7.Cu" "In8.Cu" "In9.Cu" "In10.Cu" "In11.Cu" "In12.Cu" "In13.Cu" "In14.Cu"
				"In15.Cu" "In16.Cu"
			)
			(hatch none 0.5)
			(connect_pads
				(clearance 0)
			)
			(min_thickness 0.25)
			(keepout
				(tracks not_allowed)
				(vias allowed)
				(pads allowed)
				(copperpour not_allowed)
				(footprints allowed)
			)
			(placement
				(enabled no)
				(sheetname "")
			)
			(fill
				(thermal_gap 0.5)
				(thermal_bridge_width 0.5)
				(island_removal_mode 0)
			)
			(polygon
				(pts
					(arc
						(start 271.159224 19.305524)
						(mid 269.305024 19.305524)
						(end 271.159224 19.305524)
					)
				)
			)
		)
		(zone
			(layers "F.Cu" "B.Cu" "In1.Cu" "In2.Cu" "In3.Cu" "In4.Cu" "In5.Cu" "In6.Cu"
				"In7.Cu" "In8.Cu" "In9.Cu" "In10.Cu" "In11.Cu" "In12.Cu" "In13.Cu" "In14.Cu"
				"In15.Cu" "In16.Cu"
			)
			(hatch none 0.5)
			(connect_pads
				(clearance 0)
			)
			(min_thickness 0.25)
			(keepout
				(tracks not_allowed)
				(vias allowed)
				(pads allowed)
				(copperpour not_allowed)
				(footprints allowed)
			)
			(placement
				(enabled no)
				(sheetname "")
			)
			(fill
				(thermal_gap 0.5)
				(thermal_bridge_width 0.5)
				(island_removal_mode 0)
			)
			(polygon
				(pts
					(arc
						(start 271.159224 21.845524)
						(mid 269.305024 21.845524)
						(end 271.159224 21.845524)
					)
				)
			)
		)
		(zone
			(layers "F.Cu" "B.Cu" "In1.Cu" "In2.Cu" "In3.Cu" "In4.Cu" "In5.Cu" "In6.Cu"
				"In7.Cu" "In8.Cu" "In9.Cu" "In10.Cu" "In11.Cu" "In12.Cu" "In13.Cu" "In14.Cu"
				"In15.Cu" "In16.Cu"
			)
			(hatch none 0.5)
			(connect_pads
				(clearance 0)
			)
			(min_thickness 0.25)
			(keepout
				(tracks not_allowed)
				(vias allowed)
				(pads allowed)
				(copperpour not_allowed)
				(footprints allowed)
			)
			(placement
				(enabled no)
				(sheetname "")
			)
			(fill
				(thermal_gap 0.5)
				(thermal_bridge_width 0.5)
				(island_removal_mode 0)
			)
			(polygon
				(pts
					(arc
						(start 277.509224 19.305524)
						(mid 275.655024 19.305524)
						(end 277.509224 19.305524)
					)
				)
			)
		)
		(zone
			(layers "F.Cu" "B.Cu" "In1.Cu" "In2.Cu" "In3.Cu" "In4.Cu" "In5.Cu" "In6.Cu"
				"In7.Cu" "In8.Cu" "In9.Cu" "In10.Cu" "In11.Cu" "In12.Cu" "In13.Cu" "In14.Cu"
				"In15.Cu" "In16.Cu"
			)
			(hatch none 0.5)
			(connect_pads
				(clearance 0)
			)
			(min_thickness 0.25)
			(keepout
				(tracks not_allowed)
				(vias allowed)
				(pads allowed)
				(copperpour not_allowed)
				(footprints allowed)
			)
			(placement
				(enabled no)
				(sheetname "")
			)
			(fill
				(thermal_gap 0.5)
				(thermal_bridge_width 0.5)
				(island_removal_mode 0)
			)
			(polygon
				(pts
					(arc
						(start 277.509224 21.845524)
						(mid 275.655024 21.845524)
						(end 277.509224 21.845524)
					)
				)
			)
		)
		(zone
			(layer "B.Cu")
			(hatch none 0.5)
			(connect_pads
				(clearance 0)
			)
			(min_thickness 0.25)
			(keepout
				(tracks not_allowed)
				(vias allowed)
				(pads allowed)
				(copperpour not_allowed)
				(footprints allowed)
			)
			(placement
				(enabled no)
				(sheetname "")
			)
			(fill
				(thermal_gap 0.5)
				(thermal_bridge_width 0.5)
				(island_removal_mode 0)
			)
			(polygon
				(pts
					(xy 274.232624 21.124164) (xy 274.232624 21.02866) (xy 273.635724 21.02866) (xy 273.635724 20.62226)
					(xy 274.232624 20.62226) (xy 274.232624 20.528788) (xy 273.635724 20.528788) (xy 273.635724 20.122388)
					(xy 274.232624 20.122388) (xy 274.232624 20.026884) (xy 273.534124 20.026884) (xy 273.534124 21.124164)
				)
			)
		)
	)
	(footprint ""
		(layer "B.Cu")
		(at 296.124884 -297.79976 90)
		(property "Reference" "C1656"
			(at 0 0 90)
			(layer "B.SilkS")
			(hide yes)
			(effects
				(font
					(size 1.27 1.27)
				)
				(justify mirror)
			)
		)
		(property "Value" ""
			(at 0 0 90)
			(layer "B.Fab")
			(effects
				(font
					(size 1.27 1.27)
				)
				(justify mirror)
			)
		)
		(duplicate_pad_numbers_are_jumpers no)
		(fp_line
			(start 0.299974 -0.150114)
			(end -0.299974 -0.150114)
			(stroke
				(width 0.1)
				(type default)
			)
			(layer "B.Fab")
		)
		(fp_line
			(start -0.299974 -0.150114)
			(end -0.299974 0.150114)
			(stroke
				(width 0.1)
				(type default)
			)
			(layer "B.Fab")
		)
		(fp_line
			(start 0.299974 0.150114)
			(end 0.299974 -0.150114)
			(stroke
				(width 0.1)
				(type default)
			)
			(layer "B.Fab")
		)
		(fp_line
			(start -0.299974 0.150114)
			(end 0.299974 0.150114)
			(stroke
				(width 0.1)
				(type default)
			)
			(layer "B.Fab")
		)
		(pad "1" smd rect
			(at 0.2667 0 270)
			(size 0.3048 0.381)
			(layers "B.Cu" "B.Mask" "B.Paste")
			(net "P0V8_PEX2")
		)
		(pad "2" smd rect
			(at -0.2667 0 270)
			(size 0.3048 0.381)
			(layers "B.Cu" "B.Mask" "B.Paste")
			(net "GND")
		)
	)
	(footprint ""
		(layer "B.Cu")
		(at 61.549788 -301.599854 -90)
		(property "Reference" "C1238"
			(at 0 0 90)
			(layer "B.SilkS")
			(hide yes)
			(effects
				(font
					(size 1.27 1.27)
				)
				(justify mirror)
			)
		)
		(property "Value" ""
			(at 0 0 90)
			(layer "B.Fab")
			(effects
				(font
					(size 1.27 1.27)
				)
				(justify mirror)
			)
		)
		(duplicate_pad_numbers_are_jumpers no)
		(fp_line
			(start -0.299974 0.150114)
			(end 0.299974 0.150114)
			(stroke
				(width 0.1)
				(type default)
			)
			(layer "B.Fab")
		)
		(fp_line
			(start 0.299974 0.150114)
			(end 0.299974 -0.150114)
			(stroke
				(width 0.1)
				(type default)
			)
			(layer "B.Fab")
		)
		(fp_line
			(start -0.299974 -0.150114)
			(end -0.299974 0.150114)
			(stroke
				(width 0.1)
				(type default)
			)
			(layer "B.Fab")
		)
		(fp_line
			(start 0.299974 -0.150114)
			(end -0.299974 -0.150114)
			(stroke
				(width 0.1)
				(type default)
			)
			(layer "B.Fab")
		)
		(pad "1" smd rect
			(at 0.2667 0 90)
			(size 0.3048 0.381)
			(layers "B.Cu" "B.Mask" "B.Paste")
			(net "P0V8_SERDES_VDDA_PEX0")
		)
		(pad "2" smd rect
			(at -0.2667 0 90)
			(size 0.3048 0.381)
			(layers "B.Cu" "B.Mask" "B.Paste")
			(net "GND")
		)
	)
)
